(kicad_pcb
	(version 20241229)
	(generator "pcbnew")
	(generator_version "9.0")
	(general
		(thickness 1.63)
		(legacy_teardrops no)
	)
	(paper "A4")
	(title_block
		(title "CM4 Baseboard")
		(date "2026-01-05")
		(rev "1.1.1")
		(company "Antmicro Ltd")
		(comment 1 "www.antmicro.com")
		(comment 9 "footprint 274 of 506 (J201), pads 1-98 of 100")
	)
	(layers
		(0 "F.Cu" signal)
		(4 "In1.Cu" power)
		(6 "In2.Cu" power)
		(8 "In3.Cu" signal)
		(10 "In4.Cu" signal)
		(2 "B.Cu" signal)
		(9 "F.Adhes" user "F.Adhesive")
		(11 "B.Adhes" user "B.Adhesive")
		(13 "F.Paste" user)
		(15 "B.Paste" user)
		(5 "F.SilkS" user "F.Silkscreen")
		(7 "B.SilkS" user "B.Silkscreen")
		(1 "F.Mask" user)
		(3 "B.Mask" user)
		(17 "Dwgs.User" user "User.Drawings")
		(19 "Cmts.User" user "User.Comments")
		(21 "Eco1.User" user "User.Eco1")
		(23 "Eco2.User" user "User.Eco2")
		(25 "Edge.Cuts" user)
		(27 "Margin" user)
		(31 "F.CrtYd" user "F.Courtyard")
		(29 "B.CrtYd" user "B.Courtyard")
		(35 "F.Fab" user)
		(33 "B.Fab" user)
	)
	(footprint "antmicro-footprints:Conn_Socket_Hirose_DF40_2x50_DF40HC-3.0-100DS-0.4V"
		(layer "F.Cu")
		(at 80.020961 154.714 -90)
		(property "Reference" "J201"
			(at -10.2975 1.652999 90)
			(layer "F.SilkS")
			(effects
				(font
					(size 0.7 0.7)
					(thickness 0.15)
				)
				(justify left bottom)
			)
		)
		(property "Value" "Socket_Hirose_DF40_2x50_DF40HC-3.0-100DS-0.4V"
			(at 0 3.25 90)
			(layer "F.Fab")
			(effects
				(font
					(size 0.7 0.7)
					(thickness 0.15)
				)
				(justify left bottom)
			)
		)
		(property "Datasheet" "https://www.hirose.com/en/product/document?clcode=CL0684-4151-0-51&productname=DF40HC(3.0)-100DS-0.4V(51&series=DF40&documenttype=Catalog&lang=en&documentid=en_DF40_CAT"
			(at 0 0 270)
			(layer "F.Fab")
			(hide yes)
			(effects
				(font
					(size 1.27 1.27)
					(thickness 0.15)
				)
			)
		)
		(property "Manufacturer" "Hirose Electric"
			(at 0 0 270)
			(unlocked yes)
			(layer "F.Fab")
			(hide yes)
			(effects
				(font
					(size 1 1)
					(thickness 0.15)
				)
			)
		)
		(property "MPN" "DF40HC(3.0)-100DS-0.4V(51)"
			(at 0 0 270)
			(unlocked yes)
			(layer "F.Fab")
			(hide yes)
			(effects
				(font
					(size 1 1)
					(thickness 0.15)
				)
			)
		)
		(property "Author" "Antmicro"
			(at 0 0 270)
			(unlocked yes)
			(layer "F.Fab")
			(hide yes)
			(effects
				(font
					(size 1 1)
					(thickness 0.15)
				)
			)
		)
		(property "License" "Apache-2.0"
			(at 0 0 270)
			(unlocked yes)
			(layer "F.Fab")
			(hide yes)
			(effects
				(font
					(size 1 1)
					(thickness 0.15)
				)
			)
		)
		(property "Pitch" "0.4 mm"
			(at 0 0 270)
			(unlocked yes)
			(layer "F.Fab")
			(hide yes)
			(effects
				(font
					(size 1 1)
					(thickness 0.15)
				)
			)
		)
		(sheetname "/Compute module/")
		(sheetfile "compute-module.kicad_sch")
		(attr smd)
		(pad "1" smd rect
			(at -9.798 1.547 270)
			(size 0.2 0.7)
			(layers "F.Cu" "F.Mask" "F.Paste")
			(net 3 "GND")
			(pintype "passive")
		)
		(pad "2" smd rect
			(at -9.798 -1.534 270)
			(size 0.2 0.7)
			(layers "F.Cu" "F.Mask" "F.Paste")
			(net 3 "GND")
			(pintype "passive")
		)
		(pad "3" smd rect
			(at -9.398 1.547 270)
			(size 0.2 0.7)
			(layers "F.Cu" "F.Mask" "F.Paste")
			(net 79 "/Compute module/ETHERNET.D3_P")
			(pintype "passive")
		)
		(pad "4" smd rect
			(at -9.398 -1.534 270)
			(size 0.2 0.7)
			(layers "F.Cu" "F.Mask" "F.Paste")
			(net 80 "/Compute module/ETHERNET.D1_P")
			(pintype "passive")
		)
		(pad "5" smd rect
			(at -8.997 1.547 270)
			(size 0.2 0.7)
			(layers "F.Cu" "F.Mask" "F.Paste")
			(net 81 "/Compute module/ETHERNET.D3_N")
			(pintype "passive")
		)
		(pad "6" smd rect
			(at -8.997 -1.534 270)
			(size 0.2 0.7)
			(layers "F.Cu" "F.Mask" "F.Paste")
			(net 82 "/Compute module/ETHERNET.D1_N")
			(pintype "passive")
		)
		(pad "7" smd rect
			(at -8.597 1.547 270)
			(size 0.2 0.7)
			(layers "F.Cu" "F.Mask" "F.Paste")
			(net 3 "GND")
			(pintype "passive")
		)
		(pad "8" smd rect
			(at -8.597 -1.534 270)
			(size 0.2 0.7)
			(layers "F.Cu" "F.Mask" "F.Paste")
			(net 3 "GND")
			(pintype "passive")
		)
		(pad "9" smd rect
			(at -8.196 1.547 270)
			(size 0.2 0.7)
			(layers "F.Cu" "F.Mask" "F.Paste")
			(net 83 "/Compute module/ETHERNET.D2_N")
			(pintype "passive")
		)
		(pad "10" smd rect
			(at -8.196 -1.534 270)
			(size 0.2 0.7)
			(layers "F.Cu" "F.Mask" "F.Paste")
			(net 84 "/Compute module/ETHERNET.D0_N")
			(pintype "passive")
		)
		(pad "11" smd rect
			(at -7.797 1.547 270)
			(size 0.2 0.7)
			(layers "F.Cu" "F.Mask" "F.Paste")
			(net 85 "/Compute module/ETHERNET.D2_P")
			(pintype "passive")
		)
		(pad "12" smd rect
			(at -7.797 -1.534 270)
			(size 0.2 0.7)
			(layers "F.Cu" "F.Mask" "F.Paste")
			(net 88 "/Compute module/ETHERNET.D0_P")
			(pintype "passive")
		)
		(pad "13" smd rect
			(at -7.397 1.547 270)
			(size 0.2 0.7)
			(layers "F.Cu" "F.Mask" "F.Paste")
			(net 3 "GND")
			(pintype "passive")
		)
		(pad "14" smd rect
			(at -7.397 -1.534 270)
			(size 0.2 0.7)
			(layers "F.Cu" "F.Mask" "F.Paste")
			(net 3 "GND")
			(pintype "passive")
		)
		(pad "15" smd rect
			(at -6.997 1.547 270)
			(size 0.2 0.7)
			(layers "F.Cu" "F.Mask" "F.Paste")
			(net 212 "/Compute module/ETHERNET.LED_ACT")
			(pintype "passive")
		)
		(pad "16" smd rect
			(at -6.997 -1.534 270)
			(size 0.2 0.7)
			(layers "F.Cu" "F.Mask" "F.Paste")
			(net 213 "/Compute module/SYNC_IN")
			(pintype "passive")
		)
		(pad "17" smd rect
			(at -6.596 1.547 270)
			(size 0.2 0.7)
			(layers "F.Cu" "F.Mask" "F.Paste")
			(net 214 "/Compute module/ETHERNET.LED_LINK")
			(pintype "passive")
		)
		(pad "18" smd rect
			(at -6.596 -1.534 270)
			(size 0.2 0.7)
			(layers "F.Cu" "F.Mask" "F.Paste")
			(net 215 "/Compute module/SYNC_OUT")
			(pintype "passive")
		)
		(pad "19" smd rect
			(at -6.197 1.547 270)
			(size 0.2 0.7)
			(layers "F.Cu" "F.Mask" "F.Paste")
			(net 138 "unconnected-(J201-Pad19)")
			(pintype "passive+no_connect")
		)
		(pad "20" smd rect
			(at -6.197 -1.534 270)
			(size 0.2 0.7)
			(layers "F.Cu" "F.Mask" "F.Paste")
			(net 216 "/Compute module/~{EEPROM_WP}")
			(pintype "passive")
		)
		(pad "21" smd rect
			(at -5.797 1.547 270)
			(size 0.2 0.7)
			(layers "F.Cu" "F.Mask" "F.Paste")
			(net 137 "Net-(J201-Pad21)")
			(pintype "passive")
		)
		(pad "22" smd rect
			(at -5.797 -1.534 270)
			(size 0.2 0.7)
			(layers "F.Cu" "F.Mask" "F.Paste")
			(net 3 "GND")
			(pintype "passive")
		)
		(pad "23" smd rect
			(at -5.398 1.547 270)
			(size 0.2 0.7)
			(layers "F.Cu" "F.Mask" "F.Paste")
			(net 3 "GND")
			(pintype "passive")
		)
		(pad "24" smd rect
			(at -5.398 -1.534 270)
			(size 0.2 0.7)
			(layers "F.Cu" "F.Mask" "F.Paste")
			(net 217 "/Compute module/GPIO.26")
			(pintype "passive")
		)
		(pad "25" smd rect
			(at -4.997 1.547 270)
			(size 0.2 0.7)
			(layers "F.Cu" "F.Mask" "F.Paste")
			(net 218 "/Compute module/GPIO.21")
			(pintype "passive")
		)
		(pad "26" smd rect
			(at -4.997 -1.534 270)
			(size 0.2 0.7)
			(layers "F.Cu" "F.Mask" "F.Paste")
			(net 219 "/Compute module/GPIO.19")
			(pintype "passive")
		)
		(pad "27" smd rect
			(at -4.596 1.547 270)
			(size 0.2 0.7)
			(layers "F.Cu" "F.Mask" "F.Paste")
			(net 220 "/Compute module/GPIO.20")
			(pintype "passive")
		)
		(pad "28" smd rect
			(at -4.596 -1.534 270)
			(size 0.2 0.7)
			(layers "F.Cu" "F.Mask" "F.Paste")
			(net 221 "/Compute module/GPIO.13{slash}TXD5")
			(pintype "passive")
		)
		(pad "29" smd rect
			(at -4.197 1.547 270)
			(size 0.2 0.7)
			(layers "F.Cu" "F.Mask" "F.Paste")
			(net 222 "/Compute module/GPIO.16")
			(pintype "passive")
		)
		(pad "30" smd rect
			(at -4.197 -1.534 270)
			(size 0.2 0.7)
			(layers "F.Cu" "F.Mask" "F.Paste")
			(net 223 "/Compute module/GPIO.6")
			(pintype "passive")
		)
		(pad "31" smd rect
			(at -3.795 1.547 270)
			(size 0.2 0.7)
			(layers "F.Cu" "F.Mask" "F.Paste")
			(net 224 "/Compute module/GPIO.12{slash}RXD5")
			(pintype "passive")
		)
		(pad "32" smd rect
			(at -3.795 -1.534 270)
			(size 0.2 0.7)
			(layers "F.Cu" "F.Mask" "F.Paste")
			(net 3 "GND")
			(pintype "passive")
		)
		(pad "33" smd rect
			(at -3.396 1.547 270)
			(size 0.2 0.7)
			(layers "F.Cu" "F.Mask" "F.Paste")
			(net 3 "GND")
			(pintype "passive")
		)
		(pad "34" smd rect
			(at -3.396 -1.534 270)
			(size 0.2 0.7)
			(layers "F.Cu" "F.Mask" "F.Paste")
			(net 225 "/Compute module/GPIO.5{slash}RXD3")
			(pintype "passive")
		)
		(pad "35" smd rect
			(at -2.997 1.547 270)
			(size 0.2 0.7)
			(layers "F.Cu" "F.Mask" "F.Paste")
			(net 446 "/Compute module/GPIO.1{slash}SCL0")
			(pintype "passive")
		)
		(pad "36" smd rect
			(at -2.997 -1.534 270)
			(size 0.2 0.7)
			(layers "F.Cu" "F.Mask" "F.Paste")
			(net 447 "/Compute module/GPIO.0{slash}SDA0")
			(pintype "passive")
		)
		(pad "37" smd rect
			(at -2.598 1.547 270)
			(size 0.2 0.7)
			(layers "F.Cu" "F.Mask" "F.Paste")
			(net 226 "/Compute module/GPIO.7")
			(pintype "passive")
		)
		(pad "38" smd rect
			(at -2.598 -1.534 270)
			(size 0.2 0.7)
			(layers "F.Cu" "F.Mask" "F.Paste")
			(net 227 "/Compute module/GPIO.11")
			(pintype "passive")
		)
		(pad "39" smd rect
			(at -2.198 1.547 270)
			(size 0.2 0.7)
			(layers "F.Cu" "F.Mask" "F.Paste")
			(net 228 "/Compute module/GPIO.8{slash}TXD4")
			(pintype "passive")
		)
		(pad "40" smd rect
			(at -2.198 -1.534 270)
			(size 0.2 0.7)
			(layers "F.Cu" "F.Mask" "F.Paste")
			(net 229 "/Compute module/GPIO.9{slash}RXD4")
			(pintype "passive")
		)
		(pad "41" smd rect
			(at -1.798 1.547 270)
			(size 0.2 0.7)
			(layers "F.Cu" "F.Mask" "F.Paste")
			(net 230 "/Compute module/GPIO.25")
			(pintype "passive")
		)
		(pad "42" smd rect
			(at -1.798 -1.534 270)
			(size 0.2 0.7)
			(layers "F.Cu" "F.Mask" "F.Paste")
			(net 3 "GND")
			(pintype "passive")
		)
		(pad "43" smd rect
			(at -1.396 1.547 270)
			(size 0.2 0.7)
			(layers "F.Cu" "F.Mask" "F.Paste")
			(net 231 "/Compute module/PolarfireID")
			(pintype "passive")
		)
		(pad "44" smd rect
			(at -1.396 -1.534 270)
			(size 0.2 0.7)
			(layers "F.Cu" "F.Mask" "F.Paste")
			(net 232 "/Compute module/GPIO.10")
			(pintype "passive")
		)
		(pad "45" smd rect
			(at -0.997 1.547 270)
			(size 0.2 0.7)
			(layers "F.Cu" "F.Mask" "F.Paste")
			(net 233 "/Compute module/GPIO.24")
			(pintype "passive")
		)
		(pad "46" smd rect
			(at -0.997 -1.534 270)
			(size 0.2 0.7)
			(layers "F.Cu" "F.Mask" "F.Paste")
			(net 234 "/Compute module/GPIO.22")
			(pintype "passive")
		)
		(pad "47" smd rect
			(at -0.597 1.547 270)
			(size 0.2 0.7)
			(layers "F.Cu" "F.Mask" "F.Paste")
			(net 235 "/Compute module/GPIO.23")
			(pintype "passive")
		)
		(pad "48" smd rect
			(at -0.597 -1.534 270)
			(size 0.2 0.7)
			(layers "F.Cu" "F.Mask" "F.Paste")
			(net 236 "/Compute module/GPIO.27")
			(pintype "passive")
		)
		(pad "49" smd rect
			(at -0.198 1.547 270)
			(size 0.2 0.7)
			(layers "F.Cu" "F.Mask" "F.Paste")
			(net 237 "/Compute module/GPIO.18")
			(pintype "passive")
		)
		(pad "50" smd rect
			(at -0.198 -1.534 270)
			(size 0.2 0.7)
			(layers "F.Cu" "F.Mask" "F.Paste")
			(net 238 "/Compute module/GPIO.17")
			(pintype "passive")
		)
		(pad "51" smd rect
			(at 0.203 1.547 270)
			(size 0.2 0.7)
			(layers "F.Cu" "F.Mask" "F.Paste")
			(net 239 "/Compute module/GPIO.14{slash}RXD0")
			(pintype "passive")
		)
		(pad "52" smd rect
			(at 0.203 -1.534 270)
			(size 0.2 0.7)
			(layers "F.Cu" "F.Mask" "F.Paste")
			(net 3 "GND")
			(pintype "passive")
		)
		(pad "53" smd rect
			(at 0.602 1.547 270)
			(size 0.2 0.7)
			(layers "F.Cu" "F.Mask" "F.Paste")
			(net 3 "GND")
			(pintype "passive")
		)
		(pad "54" smd rect
			(at 0.602 -1.534 270)
			(size 0.2 0.7)
			(layers "F.Cu" "F.Mask" "F.Paste")
			(net 240 "/Compute module/GPIO.4{slash}TXD3")
			(pintype "passive")
		)
		(pad "55" smd rect
			(at 1.002 1.547 270)
			(size 0.2 0.7)
			(layers "F.Cu" "F.Mask" "F.Paste")
			(net 241 "/Compute module/GPIO.15{slash}TXD0")
			(pintype "passive")
		)
		(pad "56" smd rect
			(at 1.002 -1.534 270)
			(size 0.2 0.7)
			(layers "F.Cu" "F.Mask" "F.Paste")
			(net 242 "/Compute module/GPIO.3")
			(pintype "passive")
		)
		(pad "57" smd rect
			(at 1.401 1.547 270)
			(size 0.2 0.7)
			(layers "F.Cu" "F.Mask" "F.Paste")
			(net 7 "/Compute module/SDIO.CLK")
			(pintype "passive")
		)
		(pad "58" smd rect
			(at 1.401 -1.534 270)
			(size 0.2 0.7)
			(layers "F.Cu" "F.Mask" "F.Paste")
			(net 243 "/Compute module/GPIO.2")
			(pintype "passive")
		)
		(pad "59" smd rect
			(at 1.803 1.547 270)
			(size 0.2 0.7)
			(layers "F.Cu" "F.Mask" "F.Paste")
			(net 3 "GND")
			(pintype "passive")
		)
		(pad "60" smd rect
			(at 1.803 -1.534 270)
			(size 0.2 0.7)
			(layers "F.Cu" "F.Mask" "F.Paste")
			(net 3 "GND")
			(pintype "passive")
		)
		(pad "61" smd rect
			(at 2.203 1.547 270)
			(size 0.2 0.7)
			(layers "F.Cu" "F.Mask" "F.Paste")
			(net 11 "/Compute module/SDIO.D3")
			(pintype "passive")
		)
		(pad "62" smd rect
			(at 2.203 -1.534 270)
			(size 0.2 0.7)
			(layers "F.Cu" "F.Mask" "F.Paste")
			(net 8 "/Compute module/SDIO.CMD")
			(pintype "passive")
		)
		(pad "63" smd rect
			(at 2.603 1.547 270)
			(size 0.2 0.7)
			(layers "F.Cu" "F.Mask" "F.Paste")
			(net 6 "/Compute module/SDIO.D0")
			(pintype "passive")
		)
		(pad "64" smd rect
			(at 2.603 -1.534 270)
			(size 0.2 0.7)
			(layers "F.Cu" "F.Mask" "F.Paste")
			(net 136 "unconnected-(J201-Pad64)")
			(pintype "passive+no_connect")
		)
		(pad "65" smd rect
			(at 3.002 1.547 270)
			(size 0.2 0.7)
			(layers "F.Cu" "F.Mask" "F.Paste")
			(net 3 "GND")
			(pintype "passive")
		)
		(pad "66" smd rect
			(at 3.002 -1.534 270)
			(size 0.2 0.7)
			(layers "F.Cu" "F.Mask" "F.Paste")
			(net 3 "GND")
			(pintype "passive")
		)
		(pad "67" smd rect
			(at 3.402 1.547 270)
			(size 0.2 0.7)
			(layers "F.Cu" "F.Mask" "F.Paste")
			(net 5 "/Compute module/SDIO.D1")
			(pintype "passive")
		)
		(pad "68" smd rect
			(at 3.402 -1.534 270)
			(size 0.2 0.7)
			(layers "F.Cu" "F.Mask" "F.Paste")
			(net 135 "unconnected-(J201-Pad68)")
			(pintype "passive+no_connect")
		)
		(pad "69" smd rect
			(at 3.802 1.547 270)
			(size 0.2 0.7)
			(layers "F.Cu" "F.Mask" "F.Paste")
			(net 12 "/Compute module/SDIO.D2")
			(pintype "passive")
		)
		(pad "70" smd rect
			(at 3.802 -1.534 270)
			(size 0.2 0.7)
			(layers "F.Cu" "F.Mask" "F.Paste")
			(net 134 "unconnected-(J201-Pad70)")
			(pintype "passive+no_connect")
		)
		(pad "71" smd rect
			(at 4.203 1.547 270)
			(size 0.2 0.7)
			(layers "F.Cu" "F.Mask" "F.Paste")
			(net 3 "GND")
			(pintype "passive")
		)
		(pad "72" smd rect
			(at 4.203 -1.534 270)
			(size 0.2 0.7)
			(layers "F.Cu" "F.Mask" "F.Paste")
			(net 133 "unconnected-(J201-Pad72)")
			(pintype "passive+no_connect")
		)
		(pad "73" smd rect
			(at 4.602 1.547 270)
			(size 0.2 0.7)
			(layers "F.Cu" "F.Mask" "F.Paste")
			(net 129 "Net-(J201-Pad73)")
			(pintype "passive")
		)
		(pad "74" smd rect
			(at 4.602 -1.534 270)
			(size 0.2 0.7)
			(layers "F.Cu" "F.Mask" "F.Paste")
			(net 3 "GND")
			(pintype "passive")
		)
		(pad "75" smd rect
			(at 5.002 1.547 270)
			(size 0.2 0.7)
			(layers "F.Cu" "F.Mask" "F.Paste")
			(net 131 "unconnected-(J201-Pad75)")
			(pintype "passive+no_connect")
		)
		(pad "76" smd rect
			(at 5.002 -1.534 270)
			(size 0.2 0.7)
			(layers "F.Cu" "F.Mask" "F.Paste")
			(net 130 "Net-(J201-Pad76)")
			(pintype "passive")
		)
		(pad "77" smd rect
			(at 5.403 1.547 270)
			(size 0.2 0.7)
			(layers "F.Cu" "F.Mask" "F.Paste")
			(net 10 "+5V")
			(pintype "passive")
		)
		(pad "78" smd rect
			(at 5.403 -1.534 270)
			(size 0.2 0.7)
			(layers "F.Cu" "F.Mask" "F.Paste")
			(net 18 "V_{IO}")
			(pintype "passive")
		)
		(pad "79" smd rect
			(at 5.802 1.547 270)
			(size 0.2 0.7)
			(layers "F.Cu" "F.Mask" "F.Paste")
			(net 10 "+5V")
			(pintype "passive")
		)
		(pad "80" smd rect
			(at 5.802 -1.534 270)
			(size 0.2 0.7)
			(layers "F.Cu" "F.Mask" "F.Paste")
			(net 142 "/CSI/I_{2}C1.SCL")
			(pintype "passive")
		)
		(pad "81" smd rect
			(at 6.203 1.547 270)
			(size 0.2 0.7)
			(layers "F.Cu" "F.Mask" "F.Paste")
			(net 10 "+5V")
			(pintype "passive")
		)
		(pad "82" smd rect
			(at 6.203 -1.534 270)
			(size 0.2 0.7)
			(layers "F.Cu" "F.Mask" "F.Paste")
			(net 143 "/CSI/I_{2}C1.SDA")
			(pintype "passive")
		)
		(pad "83" smd rect
			(at 6.602 1.547 270)
			(size 0.2 0.7)
			(layers "F.Cu" "F.Mask" "F.Paste")
			(net 10 "+5V")
			(pintype "passive")
		)
		(pad "84" smd rect
			(at 6.602 -1.534 270)
			(size 0.2 0.7)
			(layers "F.Cu" "F.Mask" "F.Paste")
			(net 132 "/Compute module/CM4_3V3")
			(pintype "passive")
		)
		(pad "85" smd rect
			(at 7.001 1.547 270)
			(size 0.2 0.7)
			(layers "F.Cu" "F.Mask" "F.Paste")
			(net 10 "+5V")
			(pintype "passive")
		)
		(pad "86" smd rect
			(at 7.001 -1.534 270)
			(size 0.2 0.7)
			(layers "F.Cu" "F.Mask" "F.Paste")
			(net 132 "/Compute module/CM4_3V3")
			(pintype "passive")
		)
		(pad "87" smd rect
			(at 7.403 1.547 270)
			(size 0.2 0.7)
			(layers "F.Cu" "F.Mask" "F.Paste")
			(net 10 "+5V")
			(pintype "passive")
		)
		(pad "88" smd rect
			(at 7.403 -1.534 270)
			(size 0.2 0.7)
			(layers "F.Cu" "F.Mask" "F.Paste")
			(net 22 "+1V8")
			(pintype "passive")
		)
		(pad "89" smd rect
			(at 7.802 1.547 270)
			(size 0.2 0.7)
			(layers "F.Cu" "F.Mask" "F.Paste")
			(net 247 "/Compute module/WL_nDis")
			(pintype "passive")
		)
		(pad "90" smd rect
			(at 7.802 -1.534 270)
			(size 0.2 0.7)
			(layers "F.Cu" "F.Mask" "F.Paste")
			(net 22 "+1V8")
			(pintype "passive")
		)
		(pad "91" smd rect
			(at 8.202 1.547 270)
			(size 0.2 0.7)
			(layers "F.Cu" "F.Mask" "F.Paste")
			(net 248 "/Compute module/BT_nDis")
			(pintype "passive")
		)
		(pad "92" smd rect
			(at 8.202 -1.534 270)
			(size 0.2 0.7)
			(layers "F.Cu" "F.Mask" "F.Paste")
			(net 249 "/Compute module/RUN_PG")
			(pintype "passive")
		)
		(pad "93" smd rect
			(at 8.602 1.547 270)
			(size 0.2 0.7)
			(layers "F.Cu" "F.Mask" "F.Paste")
			(net 250 "/Compute module/~{RPi_BOOT}")
			(pintype "passive")
		)
		(pad "94" smd rect
			(at 8.602 -1.534 270)
			(size 0.2 0.7)
			(layers "F.Cu" "F.Mask" "F.Paste")
			(net 251 "/Compute module/GPIO.AIN1")
			(pintype "passive")
		)
		(pad "95" smd rect
			(at 9.002 1.547 270)
			(size 0.2 0.7)
			(layers "F.Cu" "F.Mask" "F.Paste")
			(net 252 "/Compute module/~{PWR_LED}")
			(pintype "passive")
		)
		(pad "96" smd rect
			(at 9.002 -1.534 270)
			(size 0.2 0.7)
			(layers "F.Cu" "F.Mask" "F.Paste")
			(net 253 "/Compute module/GPIO.AIN0")
			(pintype "passive")
		)
		(pad "97" smd rect
			(at 9.403 1.547 270)
			(size 0.2 0.7)
			(layers "F.Cu" "F.Mask" "F.Paste")
			(net 254 "/Compute module/CAM_GPIO")
			(pintype "passive")
		)
		(pad "98" smd rect
			(at 9.403 -1.534 270)
			(size 0.2 0.7)
			(layers "F.Cu" "F.Mask" "F.Paste")
			(net 3 "GND")
			(pintype "passive")
		)
	)
)
